(kicad_pcb
	(version 20241229)
	(generator "pcbnew")
	(generator_version "9.0")
	(general
		(thickness 1.294)
		(legacy_teardrops no)
	)
	(paper "A3")
	(title_block
		(title "Kintex 410T devboard")
		(date "2024-04-03")
		(rev "1.1.2")
		(comment 9 "footprints 130-131 of 975")
	)
	(layers
		(0 "F.Cu" mixed)
		(4 "In1.Cu" power)
		(6 "In2.Cu" power)
		(8 "In3.Cu" mixed)
		(10 "In4.Cu" power)
		(12 "In5.Cu" mixed)
		(14 "In6.Cu" power)
		(16 "In7.Cu" mixed)
		(18 "In8.Cu" power)
		(2 "B.Cu" mixed)
		(9 "F.Adhes" user "F.Adhesive")
		(11 "B.Adhes" user "B.Adhesive")
		(13 "F.Paste" user)
		(15 "B.Paste" user)
		(5 "F.SilkS" user "F.Silkscreen")
		(7 "B.SilkS" user "B.Silkscreen")
		(1 "F.Mask" user)
		(3 "B.Mask" user)
		(17 "Dwgs.User" user "User.Drawings")
		(19 "Cmts.User" user "User.Comments")
		(21 "Eco1.User" user "User.Eco1")
		(23 "Eco2.User" user "User.Eco2")
		(25 "Edge.Cuts" user)
		(27 "Margin" user)
		(31 "F.CrtYd" user "F.Courtyard")
		(29 "B.CrtYd" user "B.Courtyard")
		(35 "F.Fab" user)
		(33 "B.Fab" user)
	)
	(footprint "antmicro-footprints:C_0402_1005Metric"
		(layer "F.Cu")
		(at 200.253752 99.3615 90)
		(descr "Capacitor SMD 0402")
		(tags "capacitor SMD 0402")
		(property "Reference" "C259"
			(at -9.3385 5.546248 90)
			(layer "F.SilkS")
			(effects
				(font
					(size 0.7 0.7)
					(thickness 0.15)
				)
				(justify left bottom)
			)
		)
		(property "Value" "C_100n_0402"
			(at 0 1.169 90)
			(layer "F.Fab")
			(effects
				(font
					(size 0.7 0.7)
					(thickness 0.15)
				)
				(justify left bottom)
			)
		)
		(property "Description" "SMD Multilayer Ceramic Capacitor, 0.1 µF, 50 V, 0402 [1005 Metric], ± 10%, X5R, GRM Series"
			(at 0 0 90)
			(layer "F.Fab")
			(hide yes)
			(effects
				(font
					(size 1.27 1.27)
					(thickness 0.15)
				)
			)
		)
		(property "Author" "Antmicro"
			(at 299.615252 -100.892252 0)
			(layer "F.Fab")
			(hide yes)
			(effects
				(font
					(size 1 1)
					(thickness 0.15)
				)
			)
		)
		(property "Dielectric" "X5R"
			(at 299.615252 -100.892252 0)
			(layer "F.Fab")
			(hide yes)
			(effects
				(font
					(size 1 1)
					(thickness 0.15)
				)
			)
		)
		(property "License" "Apache-2.0"
			(at 299.615252 -100.892252 0)
			(layer "F.Fab")
			(hide yes)
			(effects
				(font
					(size 1 1)
					(thickness 0.15)
				)
			)
		)
		(property "MPN" "GRM155R61H104KE14D"
			(at 299.615252 -100.892252 0)
			(layer "F.Fab")
			(hide yes)
			(effects
				(font
					(size 1 1)
					(thickness 0.15)
				)
			)
		)
		(property "Manufacturer" "Murata"
			(at 299.615252 -100.892252 0)
			(layer "F.Fab")
			(hide yes)
			(effects
				(font
					(size 1 1)
					(thickness 0.15)
				)
			)
		)
		(property "Val" "100n"
			(at 299.615252 -100.892252 0)
			(layer "F.Fab")
			(hide yes)
			(effects
				(font
					(size 1 1)
					(thickness 0.15)
				)
			)
		)
		(property "Voltage" "50V"
			(at 299.615252 -100.892252 0)
			(layer "F.Fab")
			(hide yes)
			(effects
				(font
					(size 1 1)
					(thickness 0.15)
				)
			)
		)
		(sheetname "HDMI + Ethernet")
		(sheetfile "hdmi-ethernet.kicad_sch")
		(attr smd)
		(fp_rect
			(start -0.925 -0.47)
			(end 0.925 0.47)
			(stroke
				(width 0.05)
				(type default)
			)
			(fill no)
			(layer "F.CrtYd")
		)
		(fp_line
			(start 0.504 -0.25)
			(end 0.504 0.248)
			(stroke
				(width 0.15)
				(type solid)
			)
			(layer "F.Fab")
		)
		(fp_line
			(start -0.494 -0.25)
			(end 0.504 -0.25)
			(stroke
				(width 0.15)
				(type solid)
			)
			(layer "F.Fab")
		)
		(fp_line
			(start 0.504 0.248)
			(end -0.494 0.248)
			(stroke
				(width 0.15)
				(type solid)
			)
			(layer "F.Fab")
		)
		(fp_line
			(start -0.494 0.248)
			(end -0.494 -0.25)
			(stroke
				(width 0.15)
				(type solid)
			)
			(layer "F.Fab")
		)
		(pad "1" smd roundrect
			(at -0.48 0 90)
			(size 0.59 0.64)
			(layers "F.Cu" "F.Mask" "F.Paste")
			(roundrect_rratio 0.25)
			(net 1 "GND")
			(pintype "passive")
		)
		(pad "2" smd roundrect
			(at 0.48 0 90)
			(size 0.59 0.64)
			(layers "F.Cu" "F.Mask" "F.Paste")
			(roundrect_rratio 0.25)
			(net 24 "+3V3")
			(pintype "passive")
		)
	)
	(footprint "antmicro-footprints:QFN-48-1EP_7x7x0.9mm_P0.5mm_EP5x5mm"
		(layer "F.Cu")
		(at 201.449 93.849 180)
		(property "Reference" "U27"
			(at 4.939 -5.411 180)
			(layer "F.SilkS")
			(effects
				(font
					(size 0.7 0.7)
					(thickness 0.15)
				)
				(justify left bottom)
			)
		)
		(property "Value" "KSZ9131RNXC"
			(at -10.55 5.55 180)
			(layer "F.Fab")
			(effects
				(font
					(size 0.7 0.7)
					(thickness 0.15)
				)
				(justify left bottom)
			)
		)
		(property "Description" "Ethernet ICs Gigabit Ethernet Transceiver with RGMII support"
			(at 0 0 180)
			(layer "F.Fab")
			(hide yes)
			(effects
				(font
					(size 1.27 1.27)
					(thickness 0.15)
				)
			)
		)
		(property "Author" "Antmicro"
			(at 402.898 187.698 0)
			(layer "F.Fab")
			(hide yes)
			(effects
				(font
					(size 1 1)
					(thickness 0.15)
				)
			)
		)
		(property "License" "Apache-2.0"
			(at 402.898 187.698 0)
			(layer "F.Fab")
			(hide yes)
			(effects
				(font
					(size 1 1)
					(thickness 0.15)
				)
			)
		)
		(property "MPN" "KSZ9131RNXC"
			(at 402.898 187.698 0)
			(layer "F.Fab")
			(hide yes)
			(effects
				(font
					(size 1 1)
					(thickness 0.15)
				)
			)
		)
		(property "Manufacturer" "Microchip Technology"
			(at 402.898 187.698 0)
			(layer "F.Fab")
			(hide yes)
			(effects
				(font
					(size 1 1)
					(thickness 0.15)
				)
			)
		)
		(sheetname "HDMI + Ethernet")
		(sheetfile "hdmi-ethernet.kicad_sch")
		(attr smd)
		(fp_line
			(start 3.648 3.648)
			(end 3.648 3.249)
			(stroke
				(width 0.15)
				(type solid)
			)
			(layer "F.SilkS")
		)
		(fp_line
			(start 3.648 -3.65)
			(end 3.648 -3.25)
			(stroke
				(width 0.15)
				(type solid)
			)
			(layer "F.SilkS")
		)
		(fp_line
			(start 3.249 3.648)
			(end 3.648 3.648)
			(stroke
				(width 0.15)
				(type solid)
			)
			(layer "F.SilkS")
		)
		(fp_line
			(start 3.249 -3.65)
			(end 3.648 -3.65)
			(stroke
				(width 0.15)
				(type solid)
			)
			(layer "F.SilkS")
		)
		(fp_line
			(start -3.25 3.648)
			(end -3.65 3.648)
			(stroke
				(width 0.15)
				(type solid)
			)
			(layer "F.SilkS")
		)
		(fp_line
			(start -3.25 -3.65)
			(end -3.951 -3.65)
			(stroke
				(width 0.15)
				(type solid)
			)
			(layer "F.SilkS")
		)
		(fp_line
			(start -3.65 3.648)
			(end -3.65 3.249)
			(stroke
				(width 0.15)
				(type solid)
			)
			(layer "F.SilkS")
		)
		(fp_line
			(start 4.2 4.2)
			(end -4.21 4.2)
			(stroke
				(width 0.05)
				(type solid)
			)
			(layer "F.CrtYd")
		)
		(fp_line
			(start 4.2 -4.21)
			(end 4.2 4.2)
			(stroke
				(width 0.05)
				(type solid)
			)
			(layer "F.CrtYd")
		)
		(fp_line
			(start -4.21 4.2)
			(end -4.21 -4.21)
			(stroke
				(width 0.05)
				(type solid)
			)
			(layer "F.CrtYd")
		)
		(fp_line
			(start -4.21 -4.21)
			(end 4.2 -4.21)
			(stroke
				(width 0.05)
				(type solid)
			)
			(layer "F.CrtYd")
		)
		(fp_line
			(start 3.499 3.499)
			(end 3.499 -3.5)
			(stroke
				(width 0.15)
				(type solid)
			)
			(layer "F.Fab")
		)
		(fp_line
			(start 3.499 -3.5)
			(end -2.5 -3.5)
			(stroke
				(width 0.15)
				(type solid)
			)
			(layer "F.Fab")
		)
		(fp_line
			(start -2.5 -3.5)
			(end -3.5 -2.5)
			(stroke
				(width 0.15)
				(type solid)
			)
			(layer "F.Fab")
		)
		(fp_line
			(start -3.5 3.499)
			(end 3.499 3.499)
			(stroke
				(width 0.15)
				(type solid)
			)
			(layer "F.Fab")
		)
		(fp_line
			(start -3.5 -2.5)
			(end -3.5 3.499)
			(stroke
				(width 0.15)
				(type solid)
			)
			(layer "F.Fab")
		)
		(fp_text user "."
			(at -4.4 -3.05 180)
			(layer "F.SilkS")
			(effects
				(font
					(size 0.7 0.7)
					(thickness 0.15)
				)
			)
		)
		(pad "1" smd oval
			(at -3.5 -2.75 270)
			(size 0.3 0.9)
			(layers "F.Cu" "F.Mask" "F.Paste")
			(net 717 "/HDMI + Ethernet/GBE_AVDDH")
			(pinfunction "AVDDH")
			(pintype "power_in")
		)
		(pad "2" smd oval
			(at -3.5 -2.25 270)
			(size 0.3 0.9)
			(layers "F.Cu" "F.Mask" "F.Paste")
			(net 860 "/HDMI + Ethernet/GBE1_P")
			(pinfunction "TXRXP_A")
			(pintype "input")
		)
		(pad "3" smd oval
			(at -3.5 -1.75 270)
			(size 0.3 0.9)
			(layers "F.Cu" "F.Mask" "F.Paste")
			(net 859 "/HDMI + Ethernet/GBE1_N")
			(pinfunction "TXRXM_A")
			(pintype "input")
		)
		(pad "4" smd oval
			(at -3.5 -1.25 270)
			(size 0.3 0.9)
			(layers "F.Cu" "F.Mask" "F.Paste")
			(net 728 "/HDMI + Ethernet/GBE_AVDDL{slash}PLL")
			(pinfunction "AVDDL")
			(pintype "power_in")
		)
		(pad "5" smd oval
			(at -3.5 -0.75 270)
			(size 0.3 0.9)
			(layers "F.Cu" "F.Mask" "F.Paste")
			(net 858 "/HDMI + Ethernet/GBE2_P")
			(pinfunction "TXRXP_B")
			(pintype "input")
		)
		(pad "6" smd oval
			(at -3.5 -0.25 270)
			(size 0.3 0.9)
			(layers "F.Cu" "F.Mask" "F.Paste")
			(net 857 "/HDMI + Ethernet/GBE2_N")
			(pinfunction "TXRXM_B")
			(pintype "input")
		)
		(pad "7" smd oval
			(at -3.5 0.248 270)
			(size 0.3 0.9)
			(layers "F.Cu" "F.Mask" "F.Paste")
			(net 856 "/HDMI + Ethernet/GBE3_P")
			(pinfunction "TXRXP_C")
			(pintype "input")
		)
		(pad "8" smd oval
			(at -3.5 0.748 270)
			(size 0.3 0.9)
			(layers "F.Cu" "F.Mask" "F.Paste")
			(net 855 "/HDMI + Ethernet/GBE3_N")
			(pinfunction "TXRXM_C")
			(pintype "input")
		)
		(pad "9" smd oval
			(at -3.5 1.249 270)
			(size 0.3 0.9)
			(layers "F.Cu" "F.Mask" "F.Paste")
			(net 728 "/HDMI + Ethernet/GBE_AVDDL{slash}PLL")
			(pinfunction "AVDDL")
			(pintype "passive")
		)
		(pad "10" smd oval
			(at -3.5 1.749 270)
			(size 0.3 0.9)
			(layers "F.Cu" "F.Mask" "F.Paste")
			(net 854 "/HDMI + Ethernet/GBE4_P")
			(pinfunction "TXRXP_D")
			(pintype "input")
		)
		(pad "11" smd oval
			(at -3.5 2.249 270)
			(size 0.3 0.9)
			(layers "F.Cu" "F.Mask" "F.Paste")
			(net 853 "/HDMI + Ethernet/GBE4_N")
			(pinfunction "TXRXM_D")
			(pintype "input")
		)
		(pad "12" smd oval
			(at -3.5 2.749 270)
			(size 0.3 0.9)
			(layers "F.Cu" "F.Mask" "F.Paste")
			(net 717 "/HDMI + Ethernet/GBE_AVDDH")
			(pinfunction "AVDDH")
			(pintype "passive")
		)
		(pad "13" smd oval
			(at -2.75 3.499 180)
			(size 0.3 0.9)
			(layers "F.Cu" "F.Mask" "F.Paste")
			(net 1 "GND")
			(pinfunction "NC_(GND)")
			(pintype "passive")
		)
		(pad "14" smd oval
			(at -2.25 3.499 180)
			(size 0.3 0.9)
			(layers "F.Cu" "F.Mask" "F.Paste")
			(net 727 "+1V2")
			(pinfunction "NC_(DVDDL)")
			(pintype "passive")
		)
		(pad "15" smd oval
			(at -1.75 3.499 180)
			(size 0.3 0.9)
			(layers "F.Cu" "F.Mask" "F.Paste")
			(net 850 "/HDMI + Ethernet/GBE_LED_SPD-")
			(pinfunction "LED2/PHYAD1")
			(pintype "bidirectional")
		)
		(pad "16" smd oval
			(at -1.25 3.499 180)
			(size 0.3 0.9)
			(layers "F.Cu" "F.Mask" "F.Paste")
			(net 24 "+3V3")
			(pinfunction "DVDDH")
			(pintype "power_in")
		)
		(pad "17" smd oval
			(at -0.75 3.499 180)
			(size 0.3 0.9)
			(layers "F.Cu" "F.Mask" "F.Paste")
			(net 851 "/HDMI + Ethernet/GBE_LED_LINK-")
			(pinfunction "LED1/PHAD0/PME_N1")
			(pintype "bidirectional")
		)
		(pad "18" smd oval
			(at -0.25 3.499 180)
			(size 0.3 0.9)
			(layers "F.Cu" "F.Mask" "F.Paste")
			(net 727 "+1V2")
			(pinfunction "DVDDL")
			(pintype "power_in")
		)
		(pad "19" smd oval
			(at 0.248 3.499 180)
			(size 0.3 0.9)
			(layers "F.Cu" "F.Mask" "F.Paste")
			(net 939 "/FPGA Bank 16 & 17/GBE_RGMII.TXD0")
			(pinfunction "TXD0")
			(pintype "input")
		)
		(pad "20" smd oval
			(at 0.748 3.499 180)
			(size 0.3 0.9)
			(layers "F.Cu" "F.Mask" "F.Paste")
			(net 1021 "/FPGA Bank 16 & 17/GBE_RGMII.TXD1")
			(pinfunction "TXD1")
			(pintype "input")
		)
		(pad "21" smd oval
			(at 1.249 3.499 180)
			(size 0.3 0.9)
			(layers "F.Cu" "F.Mask" "F.Paste")
			(net 1002 "/FPGA Bank 16 & 17/GBE_RGMII.TXD2")
			(pinfunction "TXD2")
			(pintype "input")
		)
		(pad "22" smd oval
			(at 1.749 3.499 180)
			(size 0.3 0.9)
			(layers "F.Cu" "F.Mask" "F.Paste")
			(net 993 "/FPGA Bank 16 & 17/GBE_RGMII.TXD3")
			(pinfunction "TXD3")
			(pintype "input")
		)
		(pad "23" smd oval
			(at 2.249 3.499 180)
			(size 0.3 0.9)
			(layers "F.Cu" "F.Mask" "F.Paste")
			(net 727 "+1V2")
			(pinfunction "DVDDL")
			(pintype "passive")
		)
		(pad "24" smd oval
			(at 2.749 3.499 180)
			(size 0.3 0.9)
			(layers "F.Cu" "F.Mask" "F.Paste")
			(net 1019 "/FPGA Bank 16 & 17/GBE_RGMII.GTX_CLK")
			(pinfunction "GTX_CLK")
			(pintype "input")
		)
		(pad "25" smd oval
			(at 3.499 2.749 270)
			(size 0.3 0.9)
			(layers "F.Cu" "F.Mask" "F.Paste")
			(net 1008 "/FPGA Bank 16 & 17/GBE_RGMII.TX_EN")
			(pinfunction "TX_EN")
			(pintype "input")
		)
		(pad "26" smd oval
			(at 3.499 2.249 270)
			(size 0.3 0.9)
			(layers "F.Cu" "F.Mask" "F.Paste")
			(net 727 "+1V2")
			(pinfunction "DVDDL")
			(pintype "passive")
		)
		(pad "27" smd oval
			(at 3.499 1.749 270)
			(size 0.3 0.9)
			(layers "F.Cu" "F.Mask" "F.Paste")
			(net 503 "/FPGA Bank 16 & 17/GBE_RGMII.RXD3")
			(pinfunction "RXD3/MODE3")
			(pintype "input")
		)
		(pad "28" smd oval
			(at 3.499 1.249 270)
			(size 0.3 0.9)
			(layers "F.Cu" "F.Mask" "F.Paste")
			(net 504 "/FPGA Bank 16 & 17/GBE_RGMII.RXD2")
			(pinfunction "RXD2/MODE2")
			(pintype "input")
		)
		(pad "29" smd oval
			(at 3.499 0.748 270)
			(size 0.3 0.9)
			(layers "F.Cu" "F.Mask" "F.Paste")
			(net 1 "GND")
			(pinfunction "GND")
			(pintype "power_out")
		)
		(pad "30" smd oval
			(at 3.499 0.248 270)
			(size 0.3 0.9)
			(layers "F.Cu" "F.Mask" "F.Paste")
			(net 727 "+1V2")
			(pinfunction "DVDDL")
			(pintype "passive")
		)
		(pad "31" smd oval
			(at 3.499 -0.25 270)
			(size 0.3 0.9)
			(layers "F.Cu" "F.Mask" "F.Paste")
			(net 505 "/FPGA Bank 16 & 17/GBE_RGMII.RXD1")
			(pinfunction "RXD1/MODE1")
			(pintype "input")
		)
		(pad "32" smd oval
			(at 3.499 -0.75 270)
			(size 0.3 0.9)
			(layers "F.Cu" "F.Mask" "F.Paste")
			(net 506 "/FPGA Bank 16 & 17/GBE_RGMII.RXD0")
			(pinfunction "RXD0/MODE0")
			(pintype "input")
		)
		(pad "33" smd oval
			(at 3.499 -1.25 270)
			(size 0.3 0.9)
			(layers "F.Cu" "F.Mask" "F.Paste")
			(net 509 "/FPGA Bank 16 & 17/GBE_RGMII.RX_DV")
			(pinfunction "RX_DV/CLK125_EN")
			(pintype "input")
		)
		(pad "34" smd oval
			(at 3.499 -1.75 270)
			(size 0.3 0.9)
			(layers "F.Cu" "F.Mask" "F.Paste")
			(net 24 "+3V3")
			(pinfunction "DVDDH")
			(pintype "passive")
		)
		(pad "35" smd oval
			(at 3.499 -2.25 270)
			(size 0.3 0.9)
			(layers "F.Cu" "F.Mask" "F.Paste")
			(net 507 "/FPGA Bank 16 & 17/GBE_RGMII.GTR_CLK")
			(pinfunction "RX_CLK/PHYAD2")
			(pintype "input")
		)
		(pad "36" smd oval
			(at 3.499 -2.75 270)
			(size 0.3 0.9)
			(layers "F.Cu" "F.Mask" "F.Paste")
			(net 1001 "/FPGA Bank 16 & 17/GBE_RGMII.MDC")
			(pinfunction "MDC")
			(pintype "input")
		)
		(pad "37" smd oval
			(at 2.749 -3.5 180)
			(size 0.3 0.9)
			(layers "F.Cu" "F.Mask" "F.Paste")
			(net 523 "/FPGA Bank 16 & 17/GBE_RGMII.MDIO")
			(pinfunction "MDIO")
			(pintype "input")
		)
		(pad "38" smd oval
			(at 2.249 -3.5 180)
			(size 0.3 0.9)
			(layers "F.Cu" "F.Mask" "F.Paste")
			(net 508 "/FPGA Bank 16 & 17/GBE_RGMII.~{INT}")
			(pinfunction "INT_N/PME_N2")
			(pintype "input")
		)
		(pad "39" smd oval
			(at 1.749 -3.5 180)
			(size 0.3 0.9)
			(layers "F.Cu" "F.Mask" "F.Paste")
			(net 727 "+1V2")
			(pinfunction "DVDDL")
			(pintype "passive")
		)
		(pad "40" smd oval
			(at 1.249 -3.5 180)
			(size 0.3 0.9)
			(layers "F.Cu" "F.Mask" "F.Paste")
			(net 24 "+3V3")
			(pinfunction "DVDDH")
			(pintype "passive")
		)
		(pad "41" smd oval
			(at 0.748 -3.5 180)
			(size 0.3 0.9)
			(layers "F.Cu" "F.Mask" "F.Paste")
			(net 510 "/FPGA Bank 16 & 17/GBE_RGMII.REFCLK")
			(pinfunction "CLK125_NDO/LED_MODE")
			(pintype "input")
		)
		(pad "42" smd oval
			(at 0.248 -3.5 180)
			(size 0.3 0.9)
			(layers "F.Cu" "F.Mask" "F.Paste")
			(net 522 "/FPGA Bank 16 & 17/GBE_RGMII.~{RESET}")
			(pinfunction "RESET_N")
			(pintype "input")
		)
		(pad "43" smd oval
			(at -0.25 -3.5 180)
			(size 0.3 0.9)
			(layers "F.Cu" "F.Mask" "F.Paste")
			(net 1404 "unconnected-(U27-LDO_O-Pad43)")
			(pinfunction "LDO_O")
			(pintype "input+no_connect")
		)
		(pad "44" smd oval
			(at -0.75 -3.5 180)
			(size 0.3 0.9)
			(layers "F.Cu" "F.Mask" "F.Paste")
			(net 728 "/HDMI + Ethernet/GBE_AVDDL{slash}PLL")
			(pinfunction "AVDDL_PLL")
			(pintype "power_in")
		)
		(pad "45" smd oval
			(at -1.25 -3.5 180)
			(size 0.3 0.9)
			(layers "F.Cu" "F.Mask" "F.Paste")
			(net 720 "/HDMI + Ethernet/GBE_XO")
			(pinfunction "XO")
			(pintype "input")
		)
		(pad "46" smd oval
			(at -1.75 -3.5 180)
			(size 0.3 0.9)
			(layers "F.Cu" "F.Mask" "F.Paste")
			(net 718 "/HDMI + Ethernet/GBE_XI")
			(pinfunction "XI")
			(pintype "input")
		)
		(pad "47" smd oval
			(at -2.25 -3.5 180)
			(size 0.3 0.9)
			(layers "F.Cu" "F.Mask" "F.Paste")
			(net 717 "/HDMI + Ethernet/GBE_AVDDH")
			(pinfunction "NC_(AVDDH)")
			(pintype "passive")
		)
		(pad "48" smd oval
			(at -2.75 -3.5 180)
			(size 0.3 0.9)
			(layers "F.Cu" "F.Mask" "F.Paste")
			(net 953 "/HDMI + Ethernet/GBE_ISET")
			(pinfunction "ISET")
			(pintype "output")
		)
		(pad "49" smd rect
			(at 0 0 180)
			(size 5 5)
			(layers "F.Cu" "F.Mask" "F.Paste")
			(net 1 "GND")
			(pinfunction "GND")
			(pintype "passive")
		)
	)
)
